(kicad_pcb
	(version 20260206)
	(generator "pcbnew")
	(generator_version "10.0")
	(general
		(thickness 1.6)
		(legacy_teardrops no)
	)
	(paper "A4")
	(title_block
		(title "04192023_DAF0TMB3IC0_F0TG_MB_C_brd_V02_OCP.brd")
		(comment 1 "Grand Teton / footprints 6882-6887 of 8354")
	)
	(layers
		(0 "F.Cu" signal "TOP")
		(4 "In1.Cu" signal "GND")
		(6 "In2.Cu" signal "IN1")
		(8 "In3.Cu" signal "GND1")
		(10 "In4.Cu" signal "IN2")
		(12 "In5.Cu" signal "GND2")
		(14 "In6.Cu" signal "IN3")
		(16 "In7.Cu" signal "GND3")
		(18 "In8.Cu" signal "VCC")
		(20 "In9.Cu" signal "VCC1")
		(22 "In10.Cu" signal "GND4")
		(24 "In11.Cu" signal "IN4")
		(26 "In12.Cu" signal "GND5")
		(28 "In13.Cu" signal "IN5")
		(30 "In14.Cu" signal "GND6")
		(32 "In15.Cu" signal "IN6")
		(34 "In16.Cu" signal "GND7")
		(2 "B.Cu" signal "BOTTOM")
		(9 "F.Adhes" user "F.Adhesive")
		(11 "B.Adhes" user "B.Adhesive")
		(13 "F.Paste" user "Package Geometry/Pastemask Top")
		(15 "B.Paste" user "Package Geometry/Pastemask Bottom")
		(5 "F.SilkS" user "Ref Des/Silkscreen Top")
		(7 "B.SilkS" user "Ref Des/Silkscreen Bottom")
		(1 "F.Mask" user "Board Geometry/Soldermask Top")
		(3 "B.Mask" user "Board Geometry/Soldermask Bottom")
		(17 "Dwgs.User" user "User.Drawings")
		(19 "Cmts.User" user "User.Comments")
		(21 "Eco1.User" user "User.Eco1")
		(23 "Eco2.User" user "User.Eco2")
		(25 "Edge.Cuts" user "Board Geometry/Outline")
		(27 "Margin" user)
		(31 "F.CrtYd" user "Package Geometry/Place Bound Top")
		(29 "B.CrtYd" user "Package Geometry/Place Bound Bottom")
		(35 "F.Fab" user "Ref Des/Assembly Top")
		(33 "B.Fab" user "Ref Des/Assembly Bottom")
	)
	(footprint ""
		(layer "B.Cu")
		(at 92.350082 -149.981666 180)
		(property "Reference" "PC244"
			(at 0 0 0)
			(layer "B.SilkS")
			(hide yes)
			(effects
				(font
					(size 1.27 1.27)
				)
				(justify mirror)
			)
		)
		(property "Value" ""
			(at 0 0 0)
			(layer "B.Fab")
			(effects
				(font
					(size 1.27 1.27)
				)
				(justify mirror)
			)
		)
		(duplicate_pad_numbers_are_jumpers no)
		(fp_line
			(start 0.7874 0.4064)
			(end 0.7874 -0.4064)
			(stroke
				(width 0.1524)
				(type default)
			)
			(layer "B.SilkS")
		)
		(fp_line
			(start 0.7874 -0.4064)
			(end -0.7874 -0.4064)
			(stroke
				(width 0.1524)
				(type default)
			)
			(layer "B.SilkS")
		)
		(fp_line
			(start -0.7874 0.4064)
			(end 0.7874 0.4064)
			(stroke
				(width 0.1524)
				(type default)
			)
			(layer "B.SilkS")
		)
		(fp_line
			(start -0.7874 -0.4064)
			(end -0.7874 0.4064)
			(stroke
				(width 0.1524)
				(type default)
			)
			(layer "B.SilkS")
		)
		(fp_line
			(start 0.67945 0.3048)
			(end 0.67945 -0.305054)
			(stroke
				(width 0.1)
				(type default)
			)
			(layer "B.Fab")
		)
		(fp_line
			(start 0.67945 -0.305054)
			(end 0.12065 -0.305054)
			(stroke
				(width 0.1)
				(type default)
			)
			(layer "B.Fab")
		)
		(fp_line
			(start 0.12065 0.3048)
			(end 0.67945 0.3048)
			(stroke
				(width 0.1)
				(type default)
			)
			(layer "B.Fab")
		)
		(fp_line
			(start 0.12065 0.2794)
			(end 0.12065 0.3048)
			(stroke
				(width 0.1)
				(type default)
			)
			(layer "B.Fab")
		)
		(fp_line
			(start 0.12065 -0.2794)
			(end -0.12065 -0.2794)
			(stroke
				(width 0.1)
				(type default)
			)
			(layer "B.Fab")
		)
		(fp_line
			(start 0.12065 -0.305054)
			(end 0.12065 -0.2794)
			(stroke
				(width 0.1)
				(type default)
			)
			(layer "B.Fab")
		)
		(fp_line
			(start -0.120396 0.3048)
			(end -0.120396 0.2794)
			(stroke
				(width 0.1)
				(type default)
			)
			(layer "B.Fab")
		)
		(fp_line
			(start -0.120396 0.2794)
			(end 0.12065 0.2794)
			(stroke
				(width 0.1)
				(type default)
			)
			(layer "B.Fab")
		)
		(fp_line
			(start -0.12065 -0.2794)
			(end -0.12065 -0.3048)
			(stroke
				(width 0.1)
				(type default)
			)
			(layer "B.Fab")
		)
		(fp_line
			(start -0.12065 -0.3048)
			(end -0.67945 -0.3048)
			(stroke
				(width 0.1)
				(type default)
			)
			(layer "B.Fab")
		)
		(fp_line
			(start -0.67945 0.3048)
			(end -0.120396 0.3048)
			(stroke
				(width 0.1)
				(type default)
			)
			(layer "B.Fab")
		)
		(fp_line
			(start -0.67945 -0.3048)
			(end -0.67945 0.3048)
			(stroke
				(width 0.1)
				(type default)
			)
			(layer "B.Fab")
		)
		(pad "1" smd circle
			(at 0.40005 0)
			(size 0 0)
			(layers "B.Cu" "B.Mask" "B.Paste")
			(net "VSENSE_PVDDCR_CPU0_P1_VSEN0")
		)
		(pad "2" smd circle
			(at -0.40005 0)
			(size 0 0)
			(layers "B.Cu" "B.Mask" "B.Paste")
			(net "VSENSE_VSS_SENSE_A_P1")
		)
	)
	(footprint ""
		(layer "B.Cu")
		(at 302.133 -354.711 180)
		(property "Reference" "PR41"
			(at 0 0 0)
			(layer "B.SilkS")
			(hide yes)
			(effects
				(font
					(size 1.27 1.27)
				)
				(justify mirror)
			)
		)
		(property "Value" ""
			(at 0 0 0)
			(layer "B.Fab")
			(effects
				(font
					(size 1.27 1.27)
				)
				(justify mirror)
			)
		)
		(duplicate_pad_numbers_are_jumpers no)
		(fp_line
			(start 0.7874 0.4064)
			(end 0.7874 -0.4064)
			(stroke
				(width 0.1524)
				(type default)
			)
			(layer "B.SilkS")
		)
		(fp_line
			(start 0.7874 -0.4064)
			(end -0.7874 -0.4064)
			(stroke
				(width 0.1524)
				(type default)
			)
			(layer "B.SilkS")
		)
		(fp_line
			(start -0.7874 0.4064)
			(end 0.7874 0.4064)
			(stroke
				(width 0.1524)
				(type default)
			)
			(layer "B.SilkS")
		)
		(fp_line
			(start -0.7874 -0.4064)
			(end -0.7874 0.4064)
			(stroke
				(width 0.1524)
				(type default)
			)
			(layer "B.SilkS")
		)
		(fp_line
			(start 0.67945 0.3048)
			(end 0.67945 -0.305054)
			(stroke
				(width 0.1)
				(type default)
			)
			(layer "B.Fab")
		)
		(fp_line
			(start 0.67945 -0.305054)
			(end 0.12065 -0.305054)
			(stroke
				(width 0.1)
				(type default)
			)
			(layer "B.Fab")
		)
		(fp_line
			(start 0.12065 0.3048)
			(end 0.67945 0.3048)
			(stroke
				(width 0.1)
				(type default)
			)
			(layer "B.Fab")
		)
		(fp_line
			(start 0.12065 0.2794)
			(end 0.12065 0.3048)
			(stroke
				(width 0.1)
				(type default)
			)
			(layer "B.Fab")
		)
		(fp_line
			(start 0.12065 -0.2794)
			(end -0.12065 -0.2794)
			(stroke
				(width 0.1)
				(type default)
			)
			(layer "B.Fab")
		)
		(fp_line
			(start 0.12065 -0.305054)
			(end 0.12065 -0.2794)
			(stroke
				(width 0.1)
				(type default)
			)
			(layer "B.Fab")
		)
		(fp_line
			(start -0.120396 0.3048)
			(end -0.120396 0.2794)
			(stroke
				(width 0.1)
				(type default)
			)
			(layer "B.Fab")
		)
		(fp_line
			(start -0.120396 0.2794)
			(end 0.12065 0.2794)
			(stroke
				(width 0.1)
				(type default)
			)
			(layer "B.Fab")
		)
		(fp_line
			(start -0.12065 -0.2794)
			(end -0.12065 -0.3048)
			(stroke
				(width 0.1)
				(type default)
			)
			(layer "B.Fab")
		)
		(fp_line
			(start -0.12065 -0.3048)
			(end -0.67945 -0.3048)
			(stroke
				(width 0.1)
				(type default)
			)
			(layer "B.Fab")
		)
		(fp_line
			(start -0.67945 0.3048)
			(end -0.120396 0.3048)
			(stroke
				(width 0.1)
				(type default)
			)
			(layer "B.Fab")
		)
		(fp_line
			(start -0.67945 -0.3048)
			(end -0.67945 0.3048)
			(stroke
				(width 0.1)
				(type default)
			)
			(layer "B.Fab")
		)
		(pad "1" smd circle
			(at 0.40005 0)
			(size 0 0)
			(layers "B.Cu" "B.Mask" "B.Paste")
			(net "PVDD18_S5_P0")
		)
		(pad "2" smd circle
			(at -0.40005 0)
			(size 0 0)
			(layers "B.Cu" "B.Mask" "B.Paste")
			(net "SVID_PVDDCR_CPU1_P0_SVTI")
		)
	)
	(footprint ""
		(layer "B.Cu")
		(at 109.575854 -256.012442 -90)
		(property "Reference" "C2263"
			(at 0 0 90)
			(layer "B.SilkS")
			(hide yes)
			(effects
				(font
					(size 1.27 1.27)
				)
				(justify mirror)
			)
		)
		(property "Value" ""
			(at 0 0 90)
			(layer "B.Fab")
			(effects
				(font
					(size 1.27 1.27)
				)
				(justify mirror)
			)
		)
		(duplicate_pad_numbers_are_jumpers no)
		(fp_line
			(start -0.7874 0.4064)
			(end 0.7874 0.4064)
			(stroke
				(width 0.1524)
				(type default)
			)
			(layer "B.SilkS")
		)
		(fp_line
			(start 0.7874 0.4064)
			(end 0.7874 -0.4064)
			(stroke
				(width 0.1524)
				(type default)
			)
			(layer "B.SilkS")
		)
		(fp_line
			(start -0.7874 -0.4064)
			(end -0.7874 0.4064)
			(stroke
				(width 0.1524)
				(type default)
			)
			(layer "B.SilkS")
		)
		(fp_line
			(start 0.7874 -0.4064)
			(end -0.7874 -0.4064)
			(stroke
				(width 0.1524)
				(type default)
			)
			(layer "B.SilkS")
		)
		(fp_line
			(start -0.67945 0.3048)
			(end -0.120396 0.3048)
			(stroke
				(width 0.1)
				(type default)
			)
			(layer "B.Fab")
		)
		(fp_line
			(start -0.120396 0.3048)
			(end -0.120396 0.2794)
			(stroke
				(width 0.1)
				(type default)
			)
			(layer "B.Fab")
		)
		(fp_line
			(start 0.12065 0.3048)
			(end 0.67945 0.3048)
			(stroke
				(width 0.1)
				(type default)
			)
			(layer "B.Fab")
		)
		(fp_line
			(start 0.67945 0.3048)
			(end 0.67945 -0.305054)
			(stroke
				(width 0.1)
				(type default)
			)
			(layer "B.Fab")
		)
		(fp_line
			(start -0.120396 0.2794)
			(end 0.12065 0.2794)
			(stroke
				(width 0.1)
				(type default)
			)
			(layer "B.Fab")
		)
		(fp_line
			(start 0.12065 0.2794)
			(end 0.12065 0.3048)
			(stroke
				(width 0.1)
				(type default)
			)
			(layer "B.Fab")
		)
		(fp_line
			(start -0.12065 -0.2794)
			(end -0.12065 -0.3048)
			(stroke
				(width 0.1)
				(type default)
			)
			(layer "B.Fab")
		)
		(fp_line
			(start 0.12065 -0.2794)
			(end -0.12065 -0.2794)
			(stroke
				(width 0.1)
				(type default)
			)
			(layer "B.Fab")
		)
		(fp_line
			(start -0.67945 -0.3048)
			(end -0.67945 0.3048)
			(stroke
				(width 0.1)
				(type default)
			)
			(layer "B.Fab")
		)
		(fp_line
			(start -0.12065 -0.3048)
			(end -0.67945 -0.3048)
			(stroke
				(width 0.1)
				(type default)
			)
			(layer "B.Fab")
		)
		(fp_line
			(start 0.12065 -0.305054)
			(end 0.12065 -0.2794)
			(stroke
				(width 0.1)
				(type default)
			)
			(layer "B.Fab")
		)
		(fp_line
			(start 0.67945 -0.305054)
			(end 0.12065 -0.305054)
			(stroke
				(width 0.1)
				(type default)
			)
			(layer "B.Fab")
		)
		(pad "1" smd circle
			(at 0.40005 0 90)
			(size 0 0)
			(layers "B.Cu" "B.Mask" "B.Paste")
			(net "PVDDCR_SOC_P1")
		)
		(pad "2" smd circle
			(at -0.40005 0 90)
			(size 0 0)
			(layers "B.Cu" "B.Mask" "B.Paste")
			(net "GND")
		)
	)
	(footprint ""
		(layer "B.Cu")
		(at 109.768386 -268.418564)
		(property "Reference" "C2404"
			(at 0 0 0)
			(layer "B.SilkS")
			(hide yes)
			(effects
				(font
					(size 1.27 1.27)
				)
				(justify mirror)
			)
		)
		(property "Value" ""
			(at 0 0 0)
			(layer "B.Fab")
			(effects
				(font
					(size 1.27 1.27)
				)
				(justify mirror)
			)
		)
		(duplicate_pad_numbers_are_jumpers no)
		(fp_line
			(start -0.7874 -0.4064)
			(end -0.7874 0.4064)
			(stroke
				(width 0.1524)
				(type default)
			)
			(layer "B.SilkS")
		)
		(fp_line
			(start -0.7874 0.4064)
			(end 0.7874 0.4064)
			(stroke
				(width 0.1524)
				(type default)
			)
			(layer "B.SilkS")
		)
		(fp_line
			(start 0.7874 -0.4064)
			(end -0.7874 -0.4064)
			(stroke
				(width 0.1524)
				(type default)
			)
			(layer "B.SilkS")
		)
		(fp_line
			(start 0.7874 0.4064)
			(end 0.7874 -0.4064)
			(stroke
				(width 0.1524)
				(type default)
			)
			(layer "B.SilkS")
		)
		(fp_line
			(start -0.67945 -0.3048)
			(end -0.67945 0.3048)
			(stroke
				(width 0.1)
				(type default)
			)
			(layer "B.Fab")
		)
		(fp_line
			(start -0.67945 0.3048)
			(end -0.120396 0.3048)
			(stroke
				(width 0.1)
				(type default)
			)
			(layer "B.Fab")
		)
		(fp_line
			(start -0.12065 -0.3048)
			(end -0.67945 -0.3048)
			(stroke
				(width 0.1)
				(type default)
			)
			(layer "B.Fab")
		)
		(fp_line
			(start -0.12065 -0.2794)
			(end -0.12065 -0.3048)
			(stroke
				(width 0.1)
				(type default)
			)
			(layer "B.Fab")
		)
		(fp_line
			(start -0.120396 0.2794)
			(end 0.12065 0.2794)
			(stroke
				(width 0.1)
				(type default)
			)
			(layer "B.Fab")
		)
		(fp_line
			(start -0.120396 0.3048)
			(end -0.120396 0.2794)
			(stroke
				(width 0.1)
				(type default)
			)
			(layer "B.Fab")
		)
		(fp_line
			(start 0.12065 -0.305054)
			(end 0.12065 -0.2794)
			(stroke
				(width 0.1)
				(type default)
			)
			(layer "B.Fab")
		)
		(fp_line
			(start 0.12065 -0.2794)
			(end -0.12065 -0.2794)
			(stroke
				(width 0.1)
				(type default)
			)
			(layer "B.Fab")
		)
		(fp_line
			(start 0.12065 0.2794)
			(end 0.12065 0.3048)
			(stroke
				(width 0.1)
				(type default)
			)
			(layer "B.Fab")
		)
		(fp_line
			(start 0.12065 0.3048)
			(end 0.67945 0.3048)
			(stroke
				(width 0.1)
				(type default)
			)
			(layer "B.Fab")
		)
		(fp_line
			(start 0.67945 -0.305054)
			(end 0.12065 -0.305054)
			(stroke
				(width 0.1)
				(type default)
			)
			(layer "B.Fab")
		)
		(fp_line
			(start 0.67945 0.3048)
			(end 0.67945 -0.305054)
			(stroke
				(width 0.1)
				(type default)
			)
			(layer "B.Fab")
		)
		(pad "1" smd circle
			(at 0.40005 0 180)
			(size 0 0)
			(layers "B.Cu" "B.Mask" "B.Paste")
			(net "PVDDCR_CPU1_P1")
		)
		(pad "2" smd circle
			(at -0.40005 0 180)
			(size 0 0)
			(layers "B.Cu" "B.Mask" "B.Paste")
			(net "GND")
		)
	)
	(footprint ""
		(layer "B.Cu")
		(at 166.327582 -413.847788 90)
		(property "Reference" "Q128"
			(at -1.578102 2.42443 270)
			(unlocked yes)
			(layer "B.SilkS")
			(effects
				(font
					(size 0.7874 0.5842)
					(thickness 0.1524)
				)
				(justify left mirror)
			)
		)
		(property "Value" ""
			(at 0 0 90)
			(layer "B.Fab")
			(effects
				(font
					(size 1.27 1.27)
				)
				(justify mirror)
			)
		)
		(duplicate_pad_numbers_are_jumpers no)
		(fp_line
			(start 1.332738 -1.100074)
			(end 0.4826 -1.100074)
			(stroke
				(width 0.1524)
				(type default)
			)
			(layer "B.SilkS")
		)
		(fp_line
			(start 0.4826 -1.100074)
			(end 0 -0.541274)
			(stroke
				(width 0.1524)
				(type default)
			)
			(layer "B.SilkS")
		)
		(fp_line
			(start -0.4826 -1.100074)
			(end -1.332738 -1.100074)
			(stroke
				(width 0.1524)
				(type default)
			)
			(layer "B.SilkS")
		)
		(fp_line
			(start -1.332738 -1.100074)
			(end -1.332738 1.100074)
			(stroke
				(width 0.1524)
				(type default)
			)
			(layer "B.SilkS")
		)
		(fp_line
			(start 0 -0.541274)
			(end -0.4826 -1.100074)
			(stroke
				(width 0.1524)
				(type default)
			)
			(layer "B.SilkS")
		)
		(fp_line
			(start 1.332738 1.100074)
			(end 1.332738 -1.100074)
			(stroke
				(width 0.1524)
				(type default)
			)
			(layer "B.SilkS")
		)
		(fp_line
			(start -1.332738 1.100074)
			(end 1.332738 1.100074)
			(stroke
				(width 0.1524)
				(type default)
			)
			(layer "B.SilkS")
		)
		(fp_poly
			(pts
				(xy 1.463802 -1.014476) (xy 2.165604 -0.663448) (xy 2.165604 -1.365504)
			)
			(stroke
				(width 0)
				(type default)
			)
			(fill yes)
			(layer "B.SilkS")
		)
		(fp_line
			(start 0.674878 -1.100074)
			(end -0.674878 -1.100074)
			(stroke
				(width 0.1)
				(type default)
			)
			(layer "B.Fab")
		)
		(fp_line
			(start -0.674878 -1.100074)
			(end -0.674878 1.100074)
			(stroke
				(width 0.1)
				(type default)
			)
			(layer "B.Fab")
		)
		(fp_line
			(start 0.674878 1.100074)
			(end 0.674878 -1.100074)
			(stroke
				(width 0.1)
				(type default)
			)
			(layer "B.Fab")
		)
		(fp_line
			(start -0.674878 1.100074)
			(end 0.674878 1.100074)
			(stroke
				(width 0.1)
				(type default)
			)
			(layer "B.Fab")
		)
		(fp_poly
			(pts
				(xy 2.2352 -0.298958) (xy 2.2352 -1.001014) (xy 1.533144 -0.649986)
			)
			(stroke
				(width 0)
				(type default)
			)
			(fill yes)
			(layer "B.Fab")
		)
		(pad "1" smd rect
			(at 0.94996 -0.649986 180)
			(size 0.4318 0.508)
			(layers "B.Cu" "B.Mask" "B.Paste")
			(net "GND")
		)
		(pad "2" smd rect
			(at 0.94996 0 180)
			(size 0.4318 0.508)
			(layers "B.Cu" "B.Mask" "B.Paste")
			(net "GPU_3V3IO_RSVD0_FFU")
		)
		(pad "3" smd rect
			(at 0.94996 0.649986 180)
			(size 0.4318 0.508)
			(layers "B.Cu" "B.Mask" "B.Paste")
			(net "GPU_3V3IO_RSVD0_FFU_ISO")
		)
		(pad "4" smd rect
			(at -0.94996 0.649986 180)
			(size 0.4318 0.508)
			(layers "B.Cu" "B.Mask" "B.Paste")
			(net "GND")
		)
		(pad "5" smd rect
			(at -0.94996 0 180)
			(size 0.4318 0.508)
			(layers "B.Cu" "B.Mask" "B.Paste")
			(net "GPU_3V3IO_RSVD0_FFU_N")
		)
		(pad "6" smd rect
			(at -0.94996 -0.649986 180)
			(size 0.4318 0.508)
			(layers "B.Cu" "B.Mask" "B.Paste")
			(net "GPU_3V3IO_RSVD0_FFU_N")
		)
	)
	(footprint ""
		(layer "B.Cu")
		(at 125.262386 -266.005564)
		(property "Reference" "C2126"
			(at 0 0 0)
			(layer "B.SilkS")
			(hide yes)
			(effects
				(font
					(size 1.27 1.27)
				)
				(justify mirror)
			)
		)
		(property "Value" ""
			(at 0 0 0)
			(layer "B.Fab")
			(effects
				(font
					(size 1.27 1.27)
				)
				(justify mirror)
			)
		)
		(duplicate_pad_numbers_are_jumpers no)
		(fp_line
			(start -0.7874 -0.4064)
			(end -0.7874 0.4064)
			(stroke
				(width 0.1524)
				(type default)
			)
			(layer "B.SilkS")
		)
		(fp_line
			(start -0.7874 0.4064)
			(end 0.7874 0.4064)
			(stroke
				(width 0.1524)
				(type default)
			)
			(layer "B.SilkS")
		)
		(fp_line
			(start 0.7874 -0.4064)
			(end -0.7874 -0.4064)
			(stroke
				(width 0.1524)
				(type default)
			)
			(layer "B.SilkS")
		)
		(fp_line
			(start 0.7874 0.4064)
			(end 0.7874 -0.4064)
			(stroke
				(width 0.1524)
				(type default)
			)
			(layer "B.SilkS")
		)
		(fp_line
			(start -0.67945 -0.3048)
			(end -0.67945 0.3048)
			(stroke
				(width 0.1)
				(type default)
			)
			(layer "B.Fab")
		)
		(fp_line
			(start -0.67945 0.3048)
			(end -0.120396 0.3048)
			(stroke
				(width 0.1)
				(type default)
			)
			(layer "B.Fab")
		)
		(fp_line
			(start -0.12065 -0.3048)
			(end -0.67945 -0.3048)
			(stroke
				(width 0.1)
				(type default)
			)
			(layer "B.Fab")
		)
		(fp_line
			(start -0.12065 -0.2794)
			(end -0.12065 -0.3048)
			(stroke
				(width 0.1)
				(type default)
			)
			(layer "B.Fab")
		)
		(fp_line
			(start -0.120396 0.2794)
			(end 0.12065 0.2794)
			(stroke
				(width 0.1)
				(type default)
			)
			(layer "B.Fab")
		)
		(fp_line
			(start -0.120396 0.3048)
			(end -0.120396 0.2794)
			(stroke
				(width 0.1)
				(type default)
			)
			(layer "B.Fab")
		)
		(fp_line
			(start 0.12065 -0.305054)
			(end 0.12065 -0.2794)
			(stroke
				(width 0.1)
				(type default)
			)
			(layer "B.Fab")
		)
		(fp_line
			(start 0.12065 -0.2794)
			(end -0.12065 -0.2794)
			(stroke
				(width 0.1)
				(type default)
			)
			(layer "B.Fab")
		)
		(fp_line
			(start 0.12065 0.2794)
			(end 0.12065 0.3048)
			(stroke
				(width 0.1)
				(type default)
			)
			(layer "B.Fab")
		)
		(fp_line
			(start 0.12065 0.3048)
			(end 0.67945 0.3048)
			(stroke
				(width 0.1)
				(type default)
			)
			(layer "B.Fab")
		)
		(fp_line
			(start 0.67945 -0.305054)
			(end 0.12065 -0.305054)
			(stroke
				(width 0.1)
				(type default)
			)
			(layer "B.Fab")
		)
		(fp_line
			(start 0.67945 0.3048)
			(end 0.67945 -0.305054)
			(stroke
				(width 0.1)
				(type default)
			)
			(layer "B.Fab")
		)
		(pad "1" smd circle
			(at 0.40005 0 180)
			(size 0 0)
			(layers "B.Cu" "B.Mask" "B.Paste")
			(net "PVDD11_S3_P1")
		)
		(pad "2" smd circle
			(at -0.40005 0 180)
			(size 0 0)
			(layers "B.Cu" "B.Mask" "B.Paste")
			(net "GND")
		)
	)
)
